(kicad_pcb
	(version 20260206)
	(generator "pcbnew")
	(generator_version "10.0")
	(general
		(thickness 1.6)
		(legacy_teardrops no)
	)
	(paper "A4")
	(title_block
		(title "01162023_DA0F0TEBIF0_F0T_Expander_BD_F_brd_V02_OCP.brd")
		(comment 1 "Grand Teton / footprints 7170-7177 of 9728")
	)
	(layers
		(0 "F.Cu" signal "TOP")
		(4 "In1.Cu" signal "GND")
		(6 "In2.Cu" signal "VCC")
		(8 "In3.Cu" signal "VCC1")
		(10 "In4.Cu" signal "GND1")
		(12 "In5.Cu" signal "IN1")
		(14 "In6.Cu" signal "GND2")
		(16 "In7.Cu" signal "IN2")
		(18 "In8.Cu" signal "GND3")
		(20 "In9.Cu" signal "IN3")
		(22 "In10.Cu" signal "GND4")
		(24 "In11.Cu" signal "IN4")
		(26 "In12.Cu" signal "GND5")
		(28 "In13.Cu" signal "IN5")
		(30 "In14.Cu" signal "GND6")
		(32 "In15.Cu" signal "IN6")
		(34 "In16.Cu" signal "GND7")
		(2 "B.Cu" signal "BOTTOM")
		(9 "F.Adhes" user "F.Adhesive")
		(11 "B.Adhes" user "B.Adhesive")
		(13 "F.Paste" user "Package Geometry/Pastemask Top")
		(15 "B.Paste" user "Package Geometry/Pastemask Bottom")
		(5 "F.SilkS" user "Ref Des/Silkscreen Top")
		(7 "B.SilkS" user "Ref Des/Silkscreen Bottom")
		(1 "F.Mask" user "Board Geometry/Soldermask Top")
		(3 "B.Mask" user "Board Geometry/Soldermask Bottom")
		(17 "Dwgs.User" user "User.Drawings")
		(19 "Cmts.User" user "User.Comments")
		(21 "Eco1.User" user "User.Eco1")
		(23 "Eco2.User" user "User.Eco2")
		(25 "Edge.Cuts" user "Board Geometry/Outline")
		(27 "Margin" user)
		(31 "F.CrtYd" user "Package Geometry/Place Bound Top")
		(29 "B.CrtYd" user "Package Geometry/Place Bound Bottom")
		(35 "F.Fab" user "Ref Des/Assembly Top")
		(33 "B.Fab" user "Ref Des/Assembly Bottom")
	)
	(footprint ""
		(layer "B.Cu")
		(at 324.612 -84.963 180)
		(property "Reference" "R6263"
			(at 0 0 0)
			(layer "B.SilkS")
			(hide yes)
			(effects
				(font
					(size 1.27 1.27)
				)
				(justify mirror)
			)
		)
		(property "Value" ""
			(at 0 0 0)
			(layer "B.Fab")
			(effects
				(font
					(size 1.27 1.27)
				)
				(justify mirror)
			)
		)
		(duplicate_pad_numbers_are_jumpers no)
		(fp_line
			(start 0.7874 0.4064)
			(end 0.7874 -0.4064)
			(stroke
				(width 0.1524)
				(type default)
			)
			(layer "B.SilkS")
		)
		(fp_line
			(start 0.7874 -0.4064)
			(end -0.7874 -0.4064)
			(stroke
				(width 0.1524)
				(type default)
			)
			(layer "B.SilkS")
		)
		(fp_line
			(start -0.7874 0.4064)
			(end 0.7874 0.4064)
			(stroke
				(width 0.1524)
				(type default)
			)
			(layer "B.SilkS")
		)
		(fp_line
			(start -0.7874 -0.4064)
			(end -0.7874 0.4064)
			(stroke
				(width 0.1524)
				(type default)
			)
			(layer "B.SilkS")
		)
		(fp_line
			(start 0.67945 0.3048)
			(end 0.67945 -0.305054)
			(stroke
				(width 0.1)
				(type default)
			)
			(layer "B.Fab")
		)
		(fp_line
			(start 0.67945 -0.305054)
			(end 0.12065 -0.305054)
			(stroke
				(width 0.1)
				(type default)
			)
			(layer "B.Fab")
		)
		(fp_line
			(start 0.12065 0.3048)
			(end 0.67945 0.3048)
			(stroke
				(width 0.1)
				(type default)
			)
			(layer "B.Fab")
		)
		(fp_line
			(start 0.12065 0.2794)
			(end 0.12065 0.3048)
			(stroke
				(width 0.1)
				(type default)
			)
			(layer "B.Fab")
		)
		(fp_line
			(start 0.12065 -0.2794)
			(end -0.12065 -0.2794)
			(stroke
				(width 0.1)
				(type default)
			)
			(layer "B.Fab")
		)
		(fp_line
			(start 0.12065 -0.305054)
			(end 0.12065 -0.2794)
			(stroke
				(width 0.1)
				(type default)
			)
			(layer "B.Fab")
		)
		(fp_line
			(start -0.120396 0.3048)
			(end -0.120396 0.2794)
			(stroke
				(width 0.1)
				(type default)
			)
			(layer "B.Fab")
		)
		(fp_line
			(start -0.120396 0.2794)
			(end 0.12065 0.2794)
			(stroke
				(width 0.1)
				(type default)
			)
			(layer "B.Fab")
		)
		(fp_line
			(start -0.12065 -0.2794)
			(end -0.12065 -0.3048)
			(stroke
				(width 0.1)
				(type default)
			)
			(layer "B.Fab")
		)
		(fp_line
			(start -0.12065 -0.3048)
			(end -0.67945 -0.3048)
			(stroke
				(width 0.1)
				(type default)
			)
			(layer "B.Fab")
		)
		(fp_line
			(start -0.67945 0.3048)
			(end -0.120396 0.3048)
			(stroke
				(width 0.1)
				(type default)
			)
			(layer "B.Fab")
		)
		(fp_line
			(start -0.67945 -0.3048)
			(end -0.67945 0.3048)
			(stroke
				(width 0.1)
				(type default)
			)
			(layer "B.Fab")
		)
		(pad "1" smd circle
			(at 0.40005 0)
			(size 0 0)
			(layers "B.Cu" "B.Mask" "B.Paste")
			(net "SMB_BIC_I2C6_MUX_FRU_R_SDA")
		)
		(pad "2" smd circle
			(at -0.40005 0)
			(size 0 0)
			(layers "B.Cu" "B.Mask" "B.Paste")
			(net "SMB_ISO_CB_SDA")
		)
	)
	(footprint ""
		(layer "B.Cu")
		(at 401.345654 -296.37482)
		(property "Reference" "C1895"
			(at 0 0 0)
			(layer "B.SilkS")
			(hide yes)
			(effects
				(font
					(size 1.27 1.27)
				)
				(justify mirror)
			)
		)
		(property "Value" ""
			(at 0 0 0)
			(layer "B.Fab")
			(effects
				(font
					(size 1.27 1.27)
				)
				(justify mirror)
			)
		)
		(duplicate_pad_numbers_are_jumpers no)
		(fp_line
			(start -0.299974 -0.150114)
			(end -0.299974 0.150114)
			(stroke
				(width 0.1)
				(type default)
			)
			(layer "B.Fab")
		)
		(fp_line
			(start -0.299974 0.150114)
			(end 0.299974 0.150114)
			(stroke
				(width 0.1)
				(type default)
			)
			(layer "B.Fab")
		)
		(fp_line
			(start 0.299974 -0.150114)
			(end -0.299974 -0.150114)
			(stroke
				(width 0.1)
				(type default)
			)
			(layer "B.Fab")
		)
		(fp_line
			(start 0.299974 0.150114)
			(end 0.299974 -0.150114)
			(stroke
				(width 0.1)
				(type default)
			)
			(layer "B.Fab")
		)
		(pad "1" smd rect
			(at 0.2667 0 180)
			(size 0.3048 0.381)
			(layers "B.Cu" "B.Mask" "B.Paste")
			(net "P0V8_PEX3")
		)
		(pad "2" smd rect
			(at -0.2667 0 180)
			(size 0.3048 0.381)
			(layers "B.Cu" "B.Mask" "B.Paste")
			(net "GND")
		)
	)
	(footprint ""
		(layer "B.Cu")
		(at 217.235786 -224.398586)
		(property "Reference" "R1494"
			(at 0 0 0)
			(layer "B.SilkS")
			(hide yes)
			(effects
				(font
					(size 1.27 1.27)
				)
				(justify mirror)
			)
		)
		(property "Value" ""
			(at 0 0 0)
			(layer "B.Fab")
			(effects
				(font
					(size 1.27 1.27)
				)
				(justify mirror)
			)
		)
		(duplicate_pad_numbers_are_jumpers no)
		(fp_line
			(start -0.7874 -0.4064)
			(end -0.7874 0.4064)
			(stroke
				(width 0.1524)
				(type default)
			)
			(layer "B.SilkS")
		)
		(fp_line
			(start -0.7874 0.4064)
			(end 0.7874 0.4064)
			(stroke
				(width 0.1524)
				(type default)
			)
			(layer "B.SilkS")
		)
		(fp_line
			(start 0.7874 -0.4064)
			(end -0.7874 -0.4064)
			(stroke
				(width 0.1524)
				(type default)
			)
			(layer "B.SilkS")
		)
		(fp_line
			(start 0.7874 0.4064)
			(end 0.7874 -0.4064)
			(stroke
				(width 0.1524)
				(type default)
			)
			(layer "B.SilkS")
		)
		(fp_line
			(start -0.67945 -0.3048)
			(end -0.67945 0.3048)
			(stroke
				(width 0.1)
				(type default)
			)
			(layer "B.Fab")
		)
		(fp_line
			(start -0.67945 0.3048)
			(end -0.120396 0.3048)
			(stroke
				(width 0.1)
				(type default)
			)
			(layer "B.Fab")
		)
		(fp_line
			(start -0.12065 -0.3048)
			(end -0.67945 -0.3048)
			(stroke
				(width 0.1)
				(type default)
			)
			(layer "B.Fab")
		)
		(fp_line
			(start -0.12065 -0.2794)
			(end -0.12065 -0.3048)
			(stroke
				(width 0.1)
				(type default)
			)
			(layer "B.Fab")
		)
		(fp_line
			(start -0.120396 0.2794)
			(end 0.12065 0.2794)
			(stroke
				(width 0.1)
				(type default)
			)
			(layer "B.Fab")
		)
		(fp_line
			(start -0.120396 0.3048)
			(end -0.120396 0.2794)
			(stroke
				(width 0.1)
				(type default)
			)
			(layer "B.Fab")
		)
		(fp_line
			(start 0.12065 -0.305054)
			(end 0.12065 -0.2794)
			(stroke
				(width 0.1)
				(type default)
			)
			(layer "B.Fab")
		)
		(fp_line
			(start 0.12065 -0.2794)
			(end -0.12065 -0.2794)
			(stroke
				(width 0.1)
				(type default)
			)
			(layer "B.Fab")
		)
		(fp_line
			(start 0.12065 0.2794)
			(end 0.12065 0.3048)
			(stroke
				(width 0.1)
				(type default)
			)
			(layer "B.Fab")
		)
		(fp_line
			(start 0.12065 0.3048)
			(end 0.67945 0.3048)
			(stroke
				(width 0.1)
				(type default)
			)
			(layer "B.Fab")
		)
		(fp_line
			(start 0.67945 -0.305054)
			(end 0.12065 -0.305054)
			(stroke
				(width 0.1)
				(type default)
			)
			(layer "B.Fab")
		)
		(fp_line
			(start 0.67945 0.3048)
			(end 0.67945 -0.305054)
			(stroke
				(width 0.1)
				(type default)
			)
			(layer "B.Fab")
		)
		(pad "1" smd circle
			(at 0.40005 0 180)
			(size 0 0)
			(layers "B.Cu" "B.Mask" "B.Paste")
			(net "SMB_BIC_I2C6_SCL")
		)
		(pad "2" smd circle
			(at -0.40005 0 180)
			(size 0 0)
			(layers "B.Cu" "B.Mask" "B.Paste")
			(net "SMB_BIC_I2C6_R_SCL")
		)
	)
	(footprint ""
		(layer "B.Cu")
		(at 231.86771 -218.30411)
		(property "Reference" "C2019"
			(at 0 0 0)
			(layer "B.SilkS")
			(hide yes)
			(effects
				(font
					(size 1.27 1.27)
				)
				(justify mirror)
			)
		)
		(property "Value" ""
			(at 0 0 0)
			(layer "B.Fab")
			(effects
				(font
					(size 1.27 1.27)
				)
				(justify mirror)
			)
		)
		(duplicate_pad_numbers_are_jumpers no)
		(fp_line
			(start -0.69215 -0.2921)
			(end -0.69215 0.2921)
			(stroke
				(width 0.1524)
				(type default)
			)
			(layer "B.SilkS")
		)
		(fp_line
			(start -0.69215 0.2921)
			(end 0.69215 0.2921)
			(stroke
				(width 0.1524)
				(type default)
			)
			(layer "B.SilkS")
		)
		(fp_line
			(start 0.69215 -0.2921)
			(end -0.69215 -0.2921)
			(stroke
				(width 0.1524)
				(type default)
			)
			(layer "B.SilkS")
		)
		(fp_line
			(start 0.69215 0.2921)
			(end 0.69215 -0.2921)
			(stroke
				(width 0.1524)
				(type default)
			)
			(layer "B.SilkS")
		)
		(fp_line
			(start -0.51435 -0.2794)
			(end -0.51435 0.2794)
			(stroke
				(width 0.1)
				(type default)
			)
			(layer "B.Fab")
		)
		(fp_line
			(start -0.51435 0.2794)
			(end 0.51435 0.2794)
			(stroke
				(width 0.1)
				(type default)
			)
			(layer "B.Fab")
		)
		(fp_line
			(start 0.51435 -0.2794)
			(end -0.51435 -0.2794)
			(stroke
				(width 0.1)
				(type default)
			)
			(layer "B.Fab")
		)
		(fp_line
			(start 0.51435 0.2794)
			(end 0.51435 -0.2794)
			(stroke
				(width 0.1)
				(type default)
			)
			(layer "B.Fab")
		)
		(pad "1" smd circle
			(at 0.40005 0 180)
			(size 0 0)
			(layers "B.Cu" "B.Mask" "B.Paste")
			(net "P1V2_AUX")
		)
		(pad "2" smd circle
			(at -0.40005 0 180)
			(size 0 0)
			(layers "B.Cu" "B.Mask" "B.Paste")
			(net "GND")
		)
		(zone
			(layer "B.Cu")
			(hatch none 0.5)
			(connect_pads
				(clearance 0)
			)
			(min_thickness 0.25)
			(keepout
				(tracks not_allowed)
				(vias allowed)
				(pads allowed)
				(copperpour not_allowed)
				(footprints allowed)
			)
			(placement
				(enabled no)
				(sheetname "")
			)
			(fill
				(thermal_gap 0.5)
				(thermal_bridge_width 0.5)
				(island_removal_mode 0)
			)
			(polygon
				(pts
					(xy 232.05821 -218.21648) (xy 231.96677 -218.158314) (xy 231.76738 -218.158314) (xy 231.67721 -218.21648)
					(xy 231.67721 -218.39174) (xy 231.76738 -218.45016) (xy 231.96677 -218.45016) (xy 232.05821 -218.391994)
				)
			)
		)
	)
	(footprint ""
		(layer "B.Cu")
		(at 55.849774 -301.599854 -90)
		(property "Reference" "C1202"
			(at 0 0 90)
			(layer "B.SilkS")
			(hide yes)
			(effects
				(font
					(size 1.27 1.27)
				)
				(justify mirror)
			)
		)
		(property "Value" ""
			(at 0 0 90)
			(layer "B.Fab")
			(effects
				(font
					(size 1.27 1.27)
				)
				(justify mirror)
			)
		)
		(duplicate_pad_numbers_are_jumpers no)
		(fp_line
			(start -0.299974 0.150114)
			(end 0.299974 0.150114)
			(stroke
				(width 0.1)
				(type default)
			)
			(layer "B.Fab")
		)
		(fp_line
			(start 0.299974 0.150114)
			(end 0.299974 -0.150114)
			(stroke
				(width 0.1)
				(type default)
			)
			(layer "B.Fab")
		)
		(fp_line
			(start -0.299974 -0.150114)
			(end -0.299974 0.150114)
			(stroke
				(width 0.1)
				(type default)
			)
			(layer "B.Fab")
		)
		(fp_line
			(start 0.299974 -0.150114)
			(end -0.299974 -0.150114)
			(stroke
				(width 0.1)
				(type default)
			)
			(layer "B.Fab")
		)
		(pad "1" smd rect
			(at 0.2667 0 90)
			(size 0.3048 0.381)
			(layers "B.Cu" "B.Mask" "B.Paste")
			(net "P0V8_SERDES_VDDA_PEX0")
		)
		(pad "2" smd rect
			(at -0.2667 0 90)
			(size 0.3048 0.381)
			(layers "B.Cu" "B.Mask" "B.Paste")
			(net "GND")
		)
	)
	(footprint ""
		(layer "B.Cu")
		(at 250.032266 -222.658432)
		(property "Reference" "C2405"
			(at 0 0 0)
			(layer "B.SilkS")
			(hide yes)
			(effects
				(font
					(size 1.27 1.27)
				)
				(justify mirror)
			)
		)
		(property "Value" ""
			(at 0 0 0)
			(layer "B.Fab")
			(effects
				(font
					(size 1.27 1.27)
				)
				(justify mirror)
			)
		)
		(duplicate_pad_numbers_are_jumpers no)
		(fp_line
			(start -0.7874 -0.4064)
			(end -0.7874 0.4064)
			(stroke
				(width 0.1524)
				(type default)
			)
			(layer "B.SilkS")
		)
		(fp_line
			(start -0.7874 0.4064)
			(end 0.7874 0.4064)
			(stroke
				(width 0.1524)
				(type default)
			)
			(layer "B.SilkS")
		)
		(fp_line
			(start 0.7874 -0.4064)
			(end -0.7874 -0.4064)
			(stroke
				(width 0.1524)
				(type default)
			)
			(layer "B.SilkS")
		)
		(fp_line
			(start 0.7874 0.4064)
			(end 0.7874 -0.4064)
			(stroke
				(width 0.1524)
				(type default)
			)
			(layer "B.SilkS")
		)
		(fp_line
			(start -0.67945 -0.3048)
			(end -0.67945 0.3048)
			(stroke
				(width 0.1)
				(type default)
			)
			(layer "B.Fab")
		)
		(fp_line
			(start -0.67945 0.3048)
			(end -0.120396 0.3048)
			(stroke
				(width 0.1)
				(type default)
			)
			(layer "B.Fab")
		)
		(fp_line
			(start -0.12065 -0.3048)
			(end -0.67945 -0.3048)
			(stroke
				(width 0.1)
				(type default)
			)
			(layer "B.Fab")
		)
		(fp_line
			(start -0.12065 -0.2794)
			(end -0.12065 -0.3048)
			(stroke
				(width 0.1)
				(type default)
			)
			(layer "B.Fab")
		)
		(fp_line
			(start -0.120396 0.2794)
			(end 0.12065 0.2794)
			(stroke
				(width 0.1)
				(type default)
			)
			(layer "B.Fab")
		)
		(fp_line
			(start -0.120396 0.3048)
			(end -0.120396 0.2794)
			(stroke
				(width 0.1)
				(type default)
			)
			(layer "B.Fab")
		)
		(fp_line
			(start 0.12065 -0.305054)
			(end 0.12065 -0.2794)
			(stroke
				(width 0.1)
				(type default)
			)
			(layer "B.Fab")
		)
		(fp_line
			(start 0.12065 -0.2794)
			(end -0.12065 -0.2794)
			(stroke
				(width 0.1)
				(type default)
			)
			(layer "B.Fab")
		)
		(fp_line
			(start 0.12065 0.2794)
			(end 0.12065 0.3048)
			(stroke
				(width 0.1)
				(type default)
			)
			(layer "B.Fab")
		)
		(fp_line
			(start 0.12065 0.3048)
			(end 0.67945 0.3048)
			(stroke
				(width 0.1)
				(type default)
			)
			(layer "B.Fab")
		)
		(fp_line
			(start 0.67945 -0.305054)
			(end 0.12065 -0.305054)
			(stroke
				(width 0.1)
				(type default)
			)
			(layer "B.Fab")
		)
		(fp_line
			(start 0.67945 0.3048)
			(end 0.67945 -0.305054)
			(stroke
				(width 0.1)
				(type default)
			)
			(layer "B.Fab")
		)
		(pad "1" smd circle
			(at 0.40005 0 180)
			(size 0 0)
			(layers "B.Cu" "B.Mask" "B.Paste")
			(net "GND")
		)
		(pad "2" smd circle
			(at -0.40005 0 180)
			(size 0 0)
			(layers "B.Cu" "B.Mask" "B.Paste")
			(net "P3V3_AUX")
		)
	)
	(footprint ""
		(layer "B.Cu")
		(at 372.974108 -222.299276 180)
		(property "Reference" "C2784"
			(at 0 0 0)
			(layer "B.SilkS")
			(hide yes)
			(effects
				(font
					(size 1.27 1.27)
				)
				(justify mirror)
			)
		)
		(property "Value" ""
			(at 0 0 0)
			(layer "B.Fab")
			(effects
				(font
					(size 1.27 1.27)
				)
				(justify mirror)
			)
		)
		(duplicate_pad_numbers_are_jumpers no)
		(fp_line
			(start 0.7874 0.4064)
			(end 0.7874 -0.4064)
			(stroke
				(width 0.1524)
				(type default)
			)
			(layer "B.SilkS")
		)
		(fp_line
			(start 0.7874 -0.4064)
			(end -0.7874 -0.4064)
			(stroke
				(width 0.1524)
				(type default)
			)
			(layer "B.SilkS")
		)
		(fp_line
			(start -0.7874 0.4064)
			(end 0.7874 0.4064)
			(stroke
				(width 0.1524)
				(type default)
			)
			(layer "B.SilkS")
		)
		(fp_line
			(start -0.7874 -0.4064)
			(end -0.7874 0.4064)
			(stroke
				(width 0.1524)
				(type default)
			)
			(layer "B.SilkS")
		)
		(fp_line
			(start 0.67945 0.3048)
			(end 0.67945 -0.305054)
			(stroke
				(width 0.1)
				(type default)
			)
			(layer "B.Fab")
		)
		(fp_line
			(start 0.67945 -0.305054)
			(end 0.12065 -0.305054)
			(stroke
				(width 0.1)
				(type default)
			)
			(layer "B.Fab")
		)
		(fp_line
			(start 0.12065 0.3048)
			(end 0.67945 0.3048)
			(stroke
				(width 0.1)
				(type default)
			)
			(layer "B.Fab")
		)
		(fp_line
			(start 0.12065 0.2794)
			(end 0.12065 0.3048)
			(stroke
				(width 0.1)
				(type default)
			)
			(layer "B.Fab")
		)
		(fp_line
			(start 0.12065 -0.2794)
			(end -0.12065 -0.2794)
			(stroke
				(width 0.1)
				(type default)
			)
			(layer "B.Fab")
		)
		(fp_line
			(start 0.12065 -0.305054)
			(end 0.12065 -0.2794)
			(stroke
				(width 0.1)
				(type default)
			)
			(layer "B.Fab")
		)
		(fp_line
			(start -0.120396 0.3048)
			(end -0.120396 0.2794)
			(stroke
				(width 0.1)
				(type default)
			)
			(layer "B.Fab")
		)
		(fp_line
			(start -0.120396 0.2794)
			(end 0.12065 0.2794)
			(stroke
				(width 0.1)
				(type default)
			)
			(layer "B.Fab")
		)
		(fp_line
			(start -0.12065 -0.2794)
			(end -0.12065 -0.3048)
			(stroke
				(width 0.1)
				(type default)
			)
			(layer "B.Fab")
		)
		(fp_line
			(start -0.12065 -0.3048)
			(end -0.67945 -0.3048)
			(stroke
				(width 0.1)
				(type default)
			)
			(layer "B.Fab")
		)
		(fp_line
			(start -0.67945 0.3048)
			(end -0.120396 0.3048)
			(stroke
				(width 0.1)
				(type default)
			)
			(layer "B.Fab")
		)
		(fp_line
			(start -0.67945 -0.3048)
			(end -0.67945 0.3048)
			(stroke
				(width 0.1)
				(type default)
			)
			(layer "B.Fab")
		)
		(pad "1" smd circle
			(at 0.40005 0)
			(size 0 0)
			(layers "B.Cu" "B.Mask" "B.Paste")
			(net "GND")
		)
		(pad "2" smd circle
			(at -0.40005 0)
			(size 0 0)
			(layers "B.Cu" "B.Mask" "B.Paste")
			(net "P1V8_PEX")
		)
	)
	(footprint ""
		(layer "B.Cu")
		(at 298.024804 -297.79976 90)
		(property "Reference" "C1629"
			(at 0 0 90)
			(layer "B.SilkS")
			(hide yes)
			(effects
				(font
					(size 1.27 1.27)
				)
				(justify mirror)
			)
		)
		(property "Value" ""
			(at 0 0 90)
			(layer "B.Fab")
			(effects
				(font
					(size 1.27 1.27)
				)
				(justify mirror)
			)
		)
		(duplicate_pad_numbers_are_jumpers no)
		(fp_line
			(start 0.299974 -0.150114)
			(end -0.299974 -0.150114)
			(stroke
				(width 0.1)
				(type default)
			)
			(layer "B.Fab")
		)
		(fp_line
			(start -0.299974 -0.150114)
			(end -0.299974 0.150114)
			(stroke
				(width 0.1)
				(type default)
			)
			(layer "B.Fab")
		)
		(fp_line
			(start 0.299974 0.150114)
			(end 0.299974 -0.150114)
			(stroke
				(width 0.1)
				(type default)
			)
			(layer "B.Fab")
		)
		(fp_line
			(start -0.299974 0.150114)
			(end 0.299974 0.150114)
			(stroke
				(width 0.1)
				(type default)
			)
			(layer "B.Fab")
		)
		(pad "1" smd rect
			(at 0.2667 0 270)
			(size 0.3048 0.381)
			(layers "B.Cu" "B.Mask" "B.Paste")
			(net "P0V8_PEX2")
		)
		(pad "2" smd rect
			(at -0.2667 0 270)
			(size 0.3048 0.381)
			(layers "B.Cu" "B.Mask" "B.Paste")
			(net "GND")
		)
	)
)
